# S9S_MB_2U (Grand Teton) — schematic netlist excerpt (pin names and nets, part order shuffled) for the footprints in the layout excerpt that follows; sources: Cadence DE-HDL packaged netlist, KiCad conversion of 03242023_DA0F0TMBIJ0_F0T_Motherboard_J_brd_V01_OCP.brd

C1809  Q_CAP  0.1UF 25V 10% X7R  pkg 0402  page 162 : A = P3V3_AUX ; B = GND
PC2214  Q_CAP  0.01UF 50V 10% EMPTY  pkg C0402  page 192 : A = P12V_E1S_0 ; B = P12V_E1S_GATE_0

(kicad_pcb
	(version 20260206)
	(generator "pcbnew")
	(generator_version "10.0")
	(general
		(thickness 1.6)
		(legacy_teardrops no)
	)
	(paper "A4")
	(title_block
		(title "03242023_DA0F0TMBIJ0_F0T_Motherboard_J_brd_V01_OCP.brd")
		(comment 1 "Grand Teton / footprints 1687-1688 of 6105")
	)
	(layers
		(0 "F.Cu" signal "TOP")
		(4 "In1.Cu" signal "GND")
		(6 "In2.Cu" signal "IN1")
		(8 "In3.Cu" signal "GND1")
		(10 "In4.Cu" signal "IN2")
		(12 "In5.Cu" signal "GND2")
		(14 "In6.Cu" signal "IN3")
		(16 "In7.Cu" signal "GND3")
		(18 "In8.Cu" signal "VCC")
		(20 "In9.Cu" signal "VCC1")
		(22 "In10.Cu" signal "GND4")
		(24 "In11.Cu" signal "IN4")
		(26 "In12.Cu" signal "GND5")
		(28 "In13.Cu" signal "IN5")
		(30 "In14.Cu" signal "GND6")
		(32 "In15.Cu" signal "IN6")
		(34 "In16.Cu" signal "GND7")
		(2 "B.Cu" signal "BOTTOM")
		(9 "F.Adhes" user "F.Adhesive")
		(11 "B.Adhes" user "B.Adhesive")
		(13 "F.Paste" user "Package Geometry/Pastemask Top")
		(15 "B.Paste" user "Package Geometry/Pastemask Bottom")
		(5 "F.SilkS" user "Ref Des/Silkscreen Top")
		(7 "B.SilkS" user "Ref Des/Silkscreen Bottom")
		(1 "F.Mask" user "Board Geometry/Soldermask Top")
		(3 "B.Mask" user "Board Geometry/Soldermask Bottom")
		(17 "Dwgs.User" user "User.Drawings")
		(19 "Cmts.User" user "User.Comments")
		(21 "Eco1.User" user "User.Eco1")
		(23 "Eco2.User" user "User.Eco2")
		(25 "Edge.Cuts" user "Board Geometry/Outline")
		(27 "Margin" user)
		(31 "F.CrtYd" user "Package Geometry/Place Bound Top")
		(29 "B.CrtYd" user "Package Geometry/Place Bound Bottom")
		(35 "F.Fab" user "Ref Des/Assembly Top")
		(33 "B.Fab" user "Ref Des/Assembly Bottom")
	)
	(footprint ""
		(layer "F.Cu")
		(at 28.578048 -76.289916)
		(property "Reference" "C1809"
			(at 0 0 0)
			(layer "F.SilkS")
			(hide yes)
			(effects
				(font
					(size 1.27 1.27)
				)
			)
		)
		(property "Value" ""
			(at 0 0 0)
			(layer "F.Fab")
			(effects
				(font
					(size 1.27 1.27)
				)
			)
		)
		(duplicate_pad_numbers_are_jumpers no)
		(fp_line
			(start -0.7874 -0.4064)
			(end 0.7874 -0.4064)
			(stroke
				(width 0.1524)
				(type default)
			)
			(layer "F.SilkS")
		)
		(fp_line
			(start -0.7874 0.4064)
			(end -0.7874 -0.4064)
			(stroke
				(width 0.1524)
				(type default)
			)
			(layer "F.SilkS")
		)
		(fp_line
			(start 0.7874 -0.4064)
			(end 0.7874 0.4064)
			(stroke
				(width 0.1524)
				(type default)
			)
			(layer "F.SilkS")
		)
		(fp_line
			(start 0.7874 0.4064)
			(end -0.7874 0.4064)
			(stroke
				(width 0.1524)
				(type default)
			)
			(layer "F.SilkS")
		)
		(fp_line
			(start -0.67945 -0.305054)
			(end -0.12065 -0.305054)
			(stroke
				(width 0.1)
				(type default)
			)
			(layer "F.Fab")
		)
		(fp_line
			(start -0.67945 0.3048)
			(end -0.67945 -0.305054)
			(stroke
				(width 0.1)
				(type default)
			)
			(layer "F.Fab")
		)
		(fp_line
			(start -0.12065 -0.305054)
			(end -0.12065 -0.2794)
			(stroke
				(width 0.1)
				(type default)
			)
			(layer "F.Fab")
		)
		(fp_line
			(start -0.12065 -0.2794)
			(end 0.12065 -0.2794)
			(stroke
				(width 0.1)
				(type default)
			)
			(layer "F.Fab")
		)
		(fp_line
			(start -0.12065 0.2794)
			(end -0.12065 0.3048)
			(stroke
				(width 0.1)
				(type default)
			)
			(layer "F.Fab")
		)
		(fp_line
			(start -0.12065 0.3048)
			(end -0.67945 0.3048)
			(stroke
				(width 0.1)
				(type default)
			)
			(layer "F.Fab")
		)
		(fp_line
			(start 0.120396 0.2794)
			(end -0.12065 0.2794)
			(stroke
				(width 0.1)
				(type default)
			)
			(layer "F.Fab")
		)
		(fp_line
			(start 0.120396 0.3048)
			(end 0.120396 0.2794)
			(stroke
				(width 0.1)
				(type default)
			)
			(layer "F.Fab")
		)
		(fp_line
			(start 0.12065 -0.3048)
			(end 0.67945 -0.3048)
			(stroke
				(width 0.1)
				(type default)
			)
			(layer "F.Fab")
		)
		(fp_line
			(start 0.12065 -0.2794)
			(end 0.12065 -0.3048)
			(stroke
				(width 0.1)
				(type default)
			)
			(layer "F.Fab")
		)
		(fp_line
			(start 0.67945 -0.3048)
			(end 0.67945 0.3048)
			(stroke
				(width 0.1)
				(type default)
			)
			(layer "F.Fab")
		)
		(fp_line
			(start 0.67945 0.3048)
			(end 0.120396 0.3048)
			(stroke
				(width 0.1)
				(type default)
			)
			(layer "F.Fab")
		)
		(pad "1" smd circle
			(at -0.40005 0)
			(size 0 0)
			(layers "F.Cu" "F.Mask" "F.Paste")
			(net "P3V3_AUX")
		)
		(pad "2" smd circle
			(at 0.40005 0)
			(size 0 0)
			(layers "F.Cu" "F.Mask" "F.Paste")
			(net "GND")
		)
	)
	(footprint ""
		(layer "F.Cu")
		(at 256.47269 -39.482522 90)
		(property "Reference" "PC2214"
			(at 0 0 90)
			(layer "F.SilkS")
			(hide yes)
			(effects
				(font
					(size 1.27 1.27)
				)
			)
		)
		(property "Value" ""
			(at 0 0 90)
			(layer "F.Fab")
			(effects
				(font
					(size 1.27 1.27)
				)
			)
		)
		(duplicate_pad_numbers_are_jumpers no)
		(fp_line
			(start 0.7874 -0.4064)
			(end 0.7874 0.4064)
			(stroke
				(width 0.1524)
				(type default)
			)
			(layer "F.SilkS")
		)
		(fp_line
			(start -0.7874 -0.4064)
			(end 0.7874 -0.4064)
			(stroke
				(width 0.1524)
				(type default)
			)
			(layer "F.SilkS")
		)
		(fp_line
			(start 0.7874 0.4064)
			(end -0.7874 0.4064)
			(stroke
				(width 0.1524)
				(type default)
			)
			(layer "F.SilkS")
		)
		(fp_line
			(start -0.7874 0.4064)
			(end -0.7874 -0.4064)
			(stroke
				(width 0.1524)
				(type default)
			)
			(layer "F.SilkS")
		)
		(fp_line
			(start -0.12065 -0.305054)
			(end -0.12065 -0.2794)
			(stroke
				(width 0.1)
				(type default)
			)
			(layer "F.Fab")
		)
		(fp_line
			(start -0.67945 -0.305054)
			(end -0.12065 -0.305054)
			(stroke
				(width 0.1)
				(type default)
			)
			(layer "F.Fab")
		)
		(fp_line
			(start 0.67945 -0.3048)
			(end 0.67945 0.3048)
			(stroke
				(width 0.1)
				(type default)
			)
			(layer "F.Fab")
		)
		(fp_line
			(start 0.12065 -0.3048)
			(end 0.67945 -0.3048)
			(stroke
				(width 0.1)
				(type default)
			)
			(layer "F.Fab")
		)
		(fp_line
			(start 0.12065 -0.2794)
			(end 0.12065 -0.3048)
			(stroke
				(width 0.1)
				(type default)
			)
			(layer "F.Fab")
		)
		(fp_line
			(start -0.12065 -0.2794)
			(end 0.12065 -0.2794)
			(stroke
				(width 0.1)
				(type default)
			)
			(layer "F.Fab")
		)
		(fp_line
			(start 0.120396 0.2794)
			(end -0.12065 0.2794)
			(stroke
				(width 0.1)
				(type default)
			)
			(layer "F.Fab")
		)
		(fp_line
			(start -0.12065 0.2794)
			(end -0.12065 0.3048)
			(stroke
				(width 0.1)
				(type default)
			)
			(layer "F.Fab")
		)
		(fp_line
			(start 0.67945 0.3048)
			(end 0.120396 0.3048)
			(stroke
				(width 0.1)
				(type default)
			)
			(layer "F.Fab")
		)
		(fp_line
			(start 0.120396 0.3048)
			(end 0.120396 0.2794)
			(stroke
				(width 0.1)
				(type default)
			)
			(layer "F.Fab")
		)
		(fp_line
			(start -0.12065 0.3048)
			(end -0.67945 0.3048)
			(stroke
				(width 0.1)
				(type default)
			)
			(layer "F.Fab")
		)
		(fp_line
			(start -0.67945 0.3048)
			(end -0.67945 -0.305054)
			(stroke
				(width 0.1)
				(type default)
			)
			(layer "F.Fab")
		)
		(pad "1" smd circle
			(at -0.40005 0 90)
			(size 0 0)
			(layers "F.Cu" "F.Mask" "F.Paste")
			(net "P12V_E1S_0")
		)
		(pad "2" smd circle
			(at 0.40005 0 90)
			(size 0 0)
			(layers "F.Cu" "F.Mask" "F.Paste")
			(net "P12V_E1S_GATE_0")
		)
	)
)
